# S9S_MB_2U (Grand Teton) — schematic netlist excerpt (pin names and nets, part order shuffled) for the footprints in the layout excerpt that follows; sources: Cadence DE-HDL packaged netlist, KiCad conversion of 03242023_DA0F0TMBIJ0_F0T_Motherboard_J_brd_V01_OCP.brd

R4153  Q_RES  10K 1% CHIP  pkg 0402LF  page 146 : A = P3V3_AUX ; B = PRSNT_CABLE_GPU_A1_N
PC277_P0_3  Q_CAP  1UF 16V 10% X6S  pkg C0402  page 268 : A = SW_P12V_PVCCIN_CPU0_FLT ; B = GND

(kicad_pcb
	(version 20260206)
	(generator "pcbnew")
	(generator_version "10.0")
	(general
		(thickness 1.6)
		(legacy_teardrops no)
	)
	(paper "A4")
	(title_block
		(title "03242023_DA0F0TMBIJ0_F0T_Motherboard_J_brd_V01_OCP.brd")
		(comment 1 "Grand Teton / footprints 1794-1795 of 6105")
	)
	(layers
		(0 "F.Cu" signal "TOP")
		(4 "In1.Cu" signal "GND")
		(6 "In2.Cu" signal "IN1")
		(8 "In3.Cu" signal "GND1")
		(10 "In4.Cu" signal "IN2")
		(12 "In5.Cu" signal "GND2")
		(14 "In6.Cu" signal "IN3")
		(16 "In7.Cu" signal "GND3")
		(18 "In8.Cu" signal "VCC")
		(20 "In9.Cu" signal "VCC1")
		(22 "In10.Cu" signal "GND4")
		(24 "In11.Cu" signal "IN4")
		(26 "In12.Cu" signal "GND5")
		(28 "In13.Cu" signal "IN5")
		(30 "In14.Cu" signal "GND6")
		(32 "In15.Cu" signal "IN6")
		(34 "In16.Cu" signal "GND7")
		(2 "B.Cu" signal "BOTTOM")
		(9 "F.Adhes" user "F.Adhesive")
		(11 "B.Adhes" user "B.Adhesive")
		(13 "F.Paste" user "Package Geometry/Pastemask Top")
		(15 "B.Paste" user "Package Geometry/Pastemask Bottom")
		(5 "F.SilkS" user "Ref Des/Silkscreen Top")
		(7 "B.SilkS" user "Ref Des/Silkscreen Bottom")
		(1 "F.Mask" user "Board Geometry/Soldermask Top")
		(3 "B.Mask" user "Board Geometry/Soldermask Bottom")
		(17 "Dwgs.User" user "User.Drawings")
		(19 "Cmts.User" user "User.Comments")
		(21 "Eco1.User" user "User.Eco1")
		(23 "Eco2.User" user "User.Eco2")
		(25 "Edge.Cuts" user "Board Geometry/Outline")
		(27 "Margin" user)
		(31 "F.CrtYd" user "Package Geometry/Place Bound Top")
		(29 "B.CrtYd" user "Package Geometry/Place Bound Bottom")
		(35 "F.Fab" user "Ref Des/Assembly Top")
		(33 "B.Fab" user "Ref Des/Assembly Bottom")
	)
	(footprint ""
		(layer "F.Cu")
		(at 364.82782 -333.804514 -90)
		(property "Reference" "PC277_P0_3"
			(at 0 0 270)
			(layer "F.SilkS")
			(hide yes)
			(effects
				(font
					(size 1.27 1.27)
				)
			)
		)
		(property "Value" ""
			(at 0 0 270)
			(layer "F.Fab")
			(effects
				(font
					(size 1.27 1.27)
				)
			)
		)
		(duplicate_pad_numbers_are_jumpers no)
		(fp_line
			(start -0.7874 0.4064)
			(end -0.7874 -0.4064)
			(stroke
				(width 0.1524)
				(type default)
			)
			(layer "F.SilkS")
		)
		(fp_line
			(start 0.7874 0.4064)
			(end -0.7874 0.4064)
			(stroke
				(width 0.1524)
				(type default)
			)
			(layer "F.SilkS")
		)
		(fp_line
			(start -0.7874 -0.4064)
			(end 0.7874 -0.4064)
			(stroke
				(width 0.1524)
				(type default)
			)
			(layer "F.SilkS")
		)
		(fp_line
			(start 0.7874 -0.4064)
			(end 0.7874 0.4064)
			(stroke
				(width 0.1524)
				(type default)
			)
			(layer "F.SilkS")
		)
		(fp_line
			(start -0.67945 0.3048)
			(end -0.67945 -0.305054)
			(stroke
				(width 0.1)
				(type default)
			)
			(layer "F.Fab")
		)
		(fp_line
			(start -0.12065 0.3048)
			(end -0.67945 0.3048)
			(stroke
				(width 0.1)
				(type default)
			)
			(layer "F.Fab")
		)
		(fp_line
			(start 0.120396 0.3048)
			(end 0.120396 0.2794)
			(stroke
				(width 0.1)
				(type default)
			)
			(layer "F.Fab")
		)
		(fp_line
			(start 0.67945 0.3048)
			(end 0.120396 0.3048)
			(stroke
				(width 0.1)
				(type default)
			)
			(layer "F.Fab")
		)
		(fp_line
			(start -0.12065 0.2794)
			(end -0.12065 0.3048)
			(stroke
				(width 0.1)
				(type default)
			)
			(layer "F.Fab")
		)
		(fp_line
			(start 0.120396 0.2794)
			(end -0.12065 0.2794)
			(stroke
				(width 0.1)
				(type default)
			)
			(layer "F.Fab")
		)
		(fp_line
			(start -0.12065 -0.2794)
			(end 0.12065 -0.2794)
			(stroke
				(width 0.1)
				(type default)
			)
			(layer "F.Fab")
		)
		(fp_line
			(start 0.12065 -0.2794)
			(end 0.12065 -0.3048)
			(stroke
				(width 0.1)
				(type default)
			)
			(layer "F.Fab")
		)
		(fp_line
			(start 0.12065 -0.3048)
			(end 0.67945 -0.3048)
			(stroke
				(width 0.1)
				(type default)
			)
			(layer "F.Fab")
		)
		(fp_line
			(start 0.67945 -0.3048)
			(end 0.67945 0.3048)
			(stroke
				(width 0.1)
				(type default)
			)
			(layer "F.Fab")
		)
		(fp_line
			(start -0.67945 -0.305054)
			(end -0.12065 -0.305054)
			(stroke
				(width 0.1)
				(type default)
			)
			(layer "F.Fab")
		)
		(fp_line
			(start -0.12065 -0.305054)
			(end -0.12065 -0.2794)
			(stroke
				(width 0.1)
				(type default)
			)
			(layer "F.Fab")
		)
		(pad "1" smd circle
			(at -0.40005 0 270)
			(size 0 0)
			(layers "F.Cu" "F.Mask" "F.Paste")
			(net "SW_P12V_PVCCIN_CPU0_FLT")
		)
		(pad "2" smd circle
			(at 0.40005 0 270)
			(size 0 0)
			(layers "F.Cu" "F.Mask" "F.Paste")
			(net "GND")
		)
	)
	(footprint ""
		(layer "F.Cu")
		(at 294.62222 -421.41521 90)
		(property "Reference" "R4153"
			(at 0 0 90)
			(layer "F.SilkS")
			(hide yes)
			(effects
				(font
					(size 1.27 1.27)
				)
			)
		)
		(property "Value" ""
			(at 0 0 90)
			(layer "F.Fab")
			(effects
				(font
					(size 1.27 1.27)
				)
			)
		)
		(duplicate_pad_numbers_are_jumpers no)
		(fp_line
			(start 0.7874 -0.4064)
			(end 0.7874 0.4064)
			(stroke
				(width 0.1524)
				(type default)
			)
			(layer "F.SilkS")
		)
		(fp_line
			(start -0.7874 -0.4064)
			(end 0.7874 -0.4064)
			(stroke
				(width 0.1524)
				(type default)
			)
			(layer "F.SilkS")
		)
		(fp_line
			(start 0.7874 0.4064)
			(end -0.7874 0.4064)
			(stroke
				(width 0.1524)
				(type default)
			)
			(layer "F.SilkS")
		)
		(fp_line
			(start -0.7874 0.4064)
			(end -0.7874 -0.4064)
			(stroke
				(width 0.1524)
				(type default)
			)
			(layer "F.SilkS")
		)
		(fp_line
			(start -0.12065 -0.305054)
			(end -0.12065 -0.2794)
			(stroke
				(width 0.1)
				(type default)
			)
			(layer "F.Fab")
		)
		(fp_line
			(start -0.67945 -0.305054)
			(end -0.12065 -0.305054)
			(stroke
				(width 0.1)
				(type default)
			)
			(layer "F.Fab")
		)
		(fp_line
			(start 0.67945 -0.3048)
			(end 0.67945 0.3048)
			(stroke
				(width 0.1)
				(type default)
			)
			(layer "F.Fab")
		)
		(fp_line
			(start 0.12065 -0.3048)
			(end 0.67945 -0.3048)
			(stroke
				(width 0.1)
				(type default)
			)
			(layer "F.Fab")
		)
		(fp_line
			(start 0.12065 -0.2794)
			(end 0.12065 -0.3048)
			(stroke
				(width 0.1)
				(type default)
			)
			(layer "F.Fab")
		)
		(fp_line
			(start -0.12065 -0.2794)
			(end 0.12065 -0.2794)
			(stroke
				(width 0.1)
				(type default)
			)
			(layer "F.Fab")
		)
		(fp_line
			(start 0.120396 0.2794)
			(end -0.12065 0.2794)
			(stroke
				(width 0.1)
				(type default)
			)
			(layer "F.Fab")
		)
		(fp_line
			(start -0.12065 0.2794)
			(end -0.12065 0.3048)
			(stroke
				(width 0.1)
				(type default)
			)
			(layer "F.Fab")
		)
		(fp_line
			(start 0.67945 0.3048)
			(end 0.120396 0.3048)
			(stroke
				(width 0.1)
				(type default)
			)
			(layer "F.Fab")
		)
		(fp_line
			(start 0.120396 0.3048)
			(end 0.120396 0.2794)
			(stroke
				(width 0.1)
				(type default)
			)
			(layer "F.Fab")
		)
		(fp_line
			(start -0.12065 0.3048)
			(end -0.67945 0.3048)
			(stroke
				(width 0.1)
				(type default)
			)
			(layer "F.Fab")
		)
		(fp_line
			(start -0.67945 0.3048)
			(end -0.67945 -0.305054)
			(stroke
				(width 0.1)
				(type default)
			)
			(layer "F.Fab")
		)
		(pad "1" smd circle
			(at -0.40005 0 90)
			(size 0 0)
			(layers "F.Cu" "F.Mask" "F.Paste")
			(net "P3V3_AUX")
		)
		(pad "2" smd circle
			(at 0.40005 0 90)
			(size 0 0)
			(layers "F.Cu" "F.Mask" "F.Paste")
			(net "PRSNT_CABLE_GPU_A1_N")
		)
	)
)
